# TIMECARD (Time Appliance Project (Time Card)) — schematic netlist excerpt (pin names and nets, part order shuffled) for the footprints in the layout excerpt that follows; sources: Cadence DE-HDL packaged netlist, KiCad conversion of R4006-B0001-02_R01.brd

C310  CAPACITOR  18PF 5%  pkg SMC_0201R  page 23 : \1\ = SG ; \2\ = UNNAMED_12_CAPACITOR_I318_2
C271  CAPACITOR  47UF 4V 20%  pkg SMC_0805R_H057  page 29 : \1\ = XP1R0V_FPGA ; \2\ = SG

(kicad_pcb
	(version 20260206)
	(generator "pcbnew")
	(generator_version "10.0")
	(general
		(thickness 1.6)
		(legacy_teardrops no)
	)
	(paper "A4")
	(title_block
		(title "timecard-production-celestica-r4006 — R4006-B0001-02_R01.brd")
		(comment 1 "Time Appliance Project (Time Card) / footprints 191-192 of 1113")
	)
	(layers
		(0 "F.Cu" signal "TOP")
		(4 "In1.Cu" signal "L02_GND1")
		(6 "In2.Cu" signal "L03_SIG1")
		(8 "In3.Cu" signal "L04_GND2")
		(10 "In4.Cu" signal "L05_VCC1")
		(12 "In5.Cu" signal "L06_VCC2")
		(14 "In6.Cu" signal "L07_GND3")
		(16 "In7.Cu" signal "L08_SIG2")
		(18 "In8.Cu" signal "L09_GND4")
		(2 "B.Cu" signal "BOTTOM")
		(9 "F.Adhes" user "F.Adhesive")
		(11 "B.Adhes" user "B.Adhesive")
		(13 "F.Paste" user "Package Geometry/Pastemask Top")
		(15 "B.Paste" user "Package Geometry/Pastemask Bottom")
		(5 "F.SilkS" user "Ref Des/Silkscreen Top")
		(7 "B.SilkS" user "Ref Des/Silkscreen Bottom")
		(1 "F.Mask" user "Board Geometry/Soldermask Top")
		(3 "B.Mask" user "Board Geometry/Soldermask Bottom")
		(17 "Dwgs.User" user "User.Drawings")
		(19 "Cmts.User" user "User.Comments")
		(21 "Eco1.User" user "User.Eco1")
		(23 "Eco2.User" user "User.Eco2")
		(25 "Edge.Cuts" user "Board Geometry/Outline")
		(27 "Margin" user)
		(31 "F.CrtYd" user "Package Geometry/Place Bound Top")
		(29 "B.CrtYd" user "Package Geometry/Place Bound Bottom")
		(35 "F.Fab" user "Ref Des/Assembly Top")
		(33 "B.Fab" user "Ref Des/Assembly Bottom")
	)
	(footprint ""
		(layer "F.Cu")
		(at 136.906 -41.402 -90)
		(property "Reference" "C271"
			(at 3.302 -0.03937 90)
			(unlocked yes)
			(layer "F.SilkS")
			(effects
				(font
					(size 0.7874 0.5842)
					(thickness 0.1524)
				)
			)
		)
		(property "Value" "VAL*"
			(at 0.0762 3.134106 270)
			(unlocked yes)
			(layer "F.Fab")
			(hide yes)
			(effects
				(font
					(size 0.7874 0.5842)
					(thickness 0.1524)
				)
			)
		)
		(property "Device Type" "CAPACITOR-G107-0F476-AM,47UF,2A"
			(at 0.0508 2.194306 270)
			(unlocked yes)
			(layer "F.Fab")
			(hide yes)
			(effects
				(font
					(size 0.7874 0.5842)
					(thickness 0.1524)
				)
			)
		)
		(property "User Part Number" "PARTNUM*"
			(at 0.1016 5.013706 270)
			(unlocked yes)
			(layer "Cmts.User")
			(hide yes)
			(effects
				(font
					(size 0.7874 0.5842)
					(thickness 0.1524)
				)
			)
		)
		(property "Tolerance" "TOL*"
			(at 0.0762 4.048506 270)
			(unlocked yes)
			(layer "Cmts.User")
			(hide yes)
			(effects
				(font
					(size 0.7874 0.5842)
					(thickness 0.1524)
				)
			)
		)
		(duplicate_pad_numbers_are_jumpers no)
		(fp_line
			(start -1.5748 0.9398)
			(end 1.5748 0.9398)
			(stroke
				(width 0.1)
				(type default)
			)
			(layer "F.SilkS")
		)
		(fp_line
			(start 1.5748 0.9398)
			(end 1.5748 -0.9398)
			(stroke
				(width 0.1)
				(type default)
			)
			(layer "F.SilkS")
		)
		(fp_line
			(start -1.5748 -0.9398)
			(end -1.5748 0.9398)
			(stroke
				(width 0.1)
				(type default)
			)
			(layer "F.SilkS")
		)
		(fp_line
			(start 1.5748 -0.9398)
			(end -1.5748 -0.9398)
			(stroke
				(width 0.1)
				(type default)
			)
			(layer "F.SilkS")
		)
		(fp_rect
			(start -1.5748 0.9398)
			(end 1.5748 -0.9398)
			(stroke
				(width 0)
				(type default)
			)
			(fill no)
			(layer "F.CrtYd")
		)
		(fp_line
			(start -1.016 0.635)
			(end 1.016 0.635)
			(stroke
				(width 0.1)
				(type default)
			)
			(layer "F.Fab")
		)
		(fp_line
			(start 1.016 0.635)
			(end 1.016 -0.635)
			(stroke
				(width 0.1)
				(type default)
			)
			(layer "F.Fab")
		)
		(fp_line
			(start -1.016 -0.635)
			(end -1.016 0.635)
			(stroke
				(width 0.1)
				(type default)
			)
			(layer "F.Fab")
		)
		(fp_line
			(start 1.016 -0.635)
			(end -1.016 -0.635)
			(stroke
				(width 0.1)
				(type default)
			)
			(layer "F.Fab")
		)
		(pad "1" smd rect
			(at -0.8382 0 270)
			(size 0.9652 1.3716)
			(layers "F.Cu" "F.Mask" "F.Paste")
			(net "XP1R0V_FPGA")
		)
		(pad "2" smd rect
			(at 0.8382 0 270)
			(size 0.9652 1.3716)
			(layers "F.Cu" "F.Mask" "F.Paste")
			(net "SG")
		)
		(zone
			(layer "F.Cu")
			(hatch none 0.5)
			(connect_pads
				(clearance 0)
			)
			(min_thickness 0.25)
			(keepout
				(tracks allowed)
				(vias not_allowed)
				(pads allowed)
				(copperpour not_allowed)
				(footprints allowed)
			)
			(placement
				(enabled no)
				(sheetname "")
			)
			(fill
				(thermal_gap 0.5)
				(thermal_bridge_width 0.5)
				(island_removal_mode 0)
			)
			(polygon
				(pts
					(xy 136.271 -41.6306) (xy 136.271 -41.1734) (xy 137.541 -41.1734) (xy 137.541 -41.6306)
				)
			)
		)
	)
	(footprint ""
		(layer "F.Cu")
		(at 12.7 -39.878 180)
		(property "Reference" "C310"
			(at -1.016 -1.04775 0)
			(unlocked yes)
			(layer "F.SilkS")
			(effects
				(font
					(size 0.635 0.4064)
					(thickness 0.1524)
				)
			)
		)
		(property "Value" "VAL*"
			(at 0.193548 2.13614 180)
			(unlocked yes)
			(layer "F.Fab")
			(hide yes)
			(effects
				(font
					(size 0.7874 0.5842)
					(thickness 0.1524)
				)
			)
		)
		(property "User Part Number" "PARTNUM*"
			(at 0.216154 4.185666 180)
			(unlocked yes)
			(layer "Cmts.User")
			(hide yes)
			(effects
				(font
					(size 0.7874 0.5842)
					(thickness 0.1524)
				)
			)
		)
		(property "Device Type" "CAPACITOR-G104-0A180-FJ,18PF,5%"
			(at 0.184404 1.180592 180)
			(unlocked yes)
			(layer "F.Fab")
			(hide yes)
			(effects
				(font
					(size 0.7874 0.5842)
					(thickness 0.1524)
				)
			)
		)
		(property "Tolerance" "TOL*"
			(at 0.216154 3.1496 180)
			(unlocked yes)
			(layer "Cmts.User")
			(hide yes)
			(effects
				(font
					(size 0.7874 0.5842)
					(thickness 0.1524)
				)
			)
		)
		(duplicate_pad_numbers_are_jumpers no)
		(fp_line
			(start 0.671322 0.4445)
			(end -0.671322 0.4445)
			(stroke
				(width 0.1)
				(type default)
			)
			(layer "F.SilkS")
		)
		(fp_line
			(start 0.671322 -0.4445)
			(end 0.671322 0.4445)
			(stroke
				(width 0.1)
				(type default)
			)
			(layer "F.SilkS")
		)
		(fp_line
			(start -0.671322 0.4445)
			(end -0.671322 -0.4445)
			(stroke
				(width 0.1)
				(type default)
			)
			(layer "F.SilkS")
		)
		(fp_line
			(start -0.671322 -0.4445)
			(end 0.671322 -0.4445)
			(stroke
				(width 0.1)
				(type default)
			)
			(layer "F.SilkS")
		)
		(fp_rect
			(start -0.671322 0.4445)
			(end 0.671322 -0.4445)
			(stroke
				(width 0)
				(type default)
			)
			(fill no)
			(layer "F.CrtYd")
		)
		(fp_line
			(start 0.31496 0.1651)
			(end 0.31496 -0.1651)
			(stroke
				(width 0.1)
				(type default)
			)
			(layer "F.Fab")
		)
		(fp_line
			(start 0.31496 -0.1651)
			(end -0.31496 -0.1651)
			(stroke
				(width 0.1)
				(type default)
			)
			(layer "F.Fab")
		)
		(fp_line
			(start -0.31496 0.1651)
			(end 0.31496 0.1651)
			(stroke
				(width 0.1)
				(type default)
			)
			(layer "F.Fab")
		)
		(fp_line
			(start -0.31496 -0.1651)
			(end -0.31496 0.1651)
			(stroke
				(width 0.1)
				(type default)
			)
			(layer "F.Fab")
		)
		(pad "1" smd rect
			(at -0.264922 0 180)
			(size 0.3048 0.381)
			(layers "F.Cu" "F.Mask" "F.Paste")
			(net "SG")
		)
		(pad "2" smd rect
			(at 0.264922 0 180)
			(size 0.3048 0.381)
			(layers "F.Cu" "F.Mask" "F.Paste")
			(net "UNNAMED_12_CAPACITOR_I318_2")
		)
		(zone
			(layer "F.Cu")
			(hatch none 0.5)
			(connect_pads
				(clearance 0)
			)
			(min_thickness 0.25)
			(keepout
				(tracks not_allowed)
				(vias allowed)
				(pads allowed)
				(copperpour not_allowed)
				(footprints allowed)
			)
			(placement
				(enabled no)
				(sheetname "")
			)
			(fill
				(thermal_gap 0.5)
				(thermal_bridge_width 0.5)
				(island_removal_mode 0)
			)
			(polygon
				(pts
					(xy 12.812522 -40.0685) (xy 12.587478 -40.0685) (xy 12.587478 -39.6875) (xy 12.812522 -39.6875)
				)
			)
		)
		(zone
			(layer "F.Cu")
			(hatch none 0.5)
			(connect_pads
				(clearance 0)
			)
			(min_thickness 0.25)
			(keepout
				(tracks allowed)
				(vias not_allowed)
				(pads allowed)
				(copperpour not_allowed)
				(footprints allowed)
			)
			(placement
				(enabled no)
				(sheetname "")
			)
			(fill
				(thermal_gap 0.5)
				(thermal_bridge_width 0.5)
				(island_removal_mode 0)
			)
			(polygon
				(pts
					(xy 12.812522 -39.6875) (xy 12.812522 -40.0685) (xy 12.587478 -40.0685) (xy 12.587478 -39.6875)
				)
			)
		)
	)
)
